FILE_TYPE = CONNECTIVITY;
{Allegro Design Entry HDL 17.2-2016 S081 (4005846) 1/11/2022}
"PAGE_NUMBER" = 153;
0"NC";
END.
